(kicad_pcb
	(version 20260206)
	(generator "pcbnew")
	(generator_version "10.0")
	(general
		(thickness 1.6)
		(legacy_teardrops no)
	)
	(paper "A4")
	(title_block
		(title "12092022_DA0F0TFB6D0_F0T_FAN_BOARD_MP5048_D_brd_v02_OCP.brd")
		(comment 1 "Grand Teton / footprints 819-824 of 924")
	)
	(layers
		(0 "F.Cu" signal "TOP")
		(4 "In1.Cu" signal "GND")
		(6 "In2.Cu" signal "IN1")
		(8 "In3.Cu" signal "IN2")
		(10 "In4.Cu" signal "GND1")
		(2 "B.Cu" signal "BOTTOM")
		(9 "F.Adhes" user "F.Adhesive")
		(11 "B.Adhes" user "B.Adhesive")
		(13 "F.Paste" user "Package Geometry/Pastemask Top")
		(15 "B.Paste" user "Package Geometry/Pastemask Bottom")
		(5 "F.SilkS" user "Ref Des/Silkscreen Top")
		(7 "B.SilkS" user "Ref Des/Silkscreen Bottom")
		(1 "F.Mask" user "Board Geometry/Soldermask Top")
		(3 "B.Mask" user "Board Geometry/Soldermask Bottom")
		(17 "Dwgs.User" user "User.Drawings")
		(19 "Cmts.User" user "User.Comments")
		(21 "Eco1.User" user "User.Eco1")
		(23 "Eco2.User" user "User.Eco2")
		(25 "Edge.Cuts" user "Board Geometry/Outline")
		(27 "Margin" user)
		(31 "F.CrtYd" user "Package Geometry/Place Bound Top")
		(29 "B.CrtYd" user "Package Geometry/Place Bound Bottom")
		(35 "F.Fab" user "Ref Des/Assembly Top")
		(33 "B.Fab" user "Ref Des/Assembly Bottom")
	)
	(footprint ""
		(layer "B.Cu")
		(at 10.329418 -60.382912 -90)
		(property "Reference" "PC61"
			(at 0 0 90)
			(layer "B.SilkS")
			(hide yes)
			(effects
				(font
					(size 1.27 1.27)
				)
				(justify mirror)
			)
		)
		(property "Value" ""
			(at 0 0 90)
			(layer "B.Fab")
			(effects
				(font
					(size 1.27 1.27)
				)
				(justify mirror)
			)
		)
		(duplicate_pad_numbers_are_jumpers no)
		(fp_line
			(start -1.524 0.762)
			(end 1.524 0.762)
			(stroke
				(width 0.1524)
				(type default)
			)
			(layer "B.SilkS")
		)
		(fp_line
			(start 1.524 0.762)
			(end 1.524 -0.762)
			(stroke
				(width 0.1524)
				(type default)
			)
			(layer "B.SilkS")
		)
		(fp_line
			(start -1.524 -0.762)
			(end -1.524 0.762)
			(stroke
				(width 0.1524)
				(type default)
			)
			(layer "B.SilkS")
		)
		(fp_line
			(start 1.524 -0.762)
			(end -1.524 -0.762)
			(stroke
				(width 0.1524)
				(type default)
			)
			(layer "B.SilkS")
		)
		(fp_line
			(start -1.1049 0.724916)
			(end -1.1049 -0.724916)
			(stroke
				(width 0.1)
				(type default)
			)
			(layer "B.Fab")
		)
		(fp_line
			(start 1.1049 0.724916)
			(end -1.1049 0.724916)
			(stroke
				(width 0.1)
				(type default)
			)
			(layer "B.Fab")
		)
		(fp_line
			(start -1.1049 -0.724916)
			(end 1.1049 -0.724916)
			(stroke
				(width 0.1)
				(type default)
			)
			(layer "B.Fab")
		)
		(fp_line
			(start 1.1049 -0.724916)
			(end 1.1049 0.724916)
			(stroke
				(width 0.1)
				(type default)
			)
			(layer "B.Fab")
		)
		(pad "1" smd rect
			(at 0.889 0 270)
			(size 1.016 1.27)
			(layers "B.Cu" "B.Mask" "B.Paste")
			(net "P52V_HSC")
		)
		(pad "2" smd rect
			(at -0.889 0 270)
			(size 1.016 1.27)
			(layers "B.Cu" "B.Mask" "B.Paste")
			(net "GND")
		)
	)
	(footprint ""
		(layer "B.Cu")
		(at 9.906 -171.831 180)
		(property "Reference" "C1939"
			(at 0 0 0)
			(layer "B.SilkS")
			(hide yes)
			(effects
				(font
					(size 1.27 1.27)
				)
				(justify mirror)
			)
		)
		(property "Value" ""
			(at 0 0 0)
			(layer "B.Fab")
			(effects
				(font
					(size 1.27 1.27)
				)
				(justify mirror)
			)
		)
		(duplicate_pad_numbers_are_jumpers no)
		(fp_line
			(start 0.7874 0.4064)
			(end 0.7874 -0.4064)
			(stroke
				(width 0.1524)
				(type default)
			)
			(layer "B.SilkS")
		)
		(fp_line
			(start 0.7874 -0.4064)
			(end -0.7874 -0.4064)
			(stroke
				(width 0.1524)
				(type default)
			)
			(layer "B.SilkS")
		)
		(fp_line
			(start -0.7874 0.4064)
			(end 0.7874 0.4064)
			(stroke
				(width 0.1524)
				(type default)
			)
			(layer "B.SilkS")
		)
		(fp_line
			(start -0.7874 -0.4064)
			(end -0.7874 0.4064)
			(stroke
				(width 0.1524)
				(type default)
			)
			(layer "B.SilkS")
		)
		(fp_line
			(start 0.67945 0.3048)
			(end 0.67945 -0.305054)
			(stroke
				(width 0.1)
				(type default)
			)
			(layer "B.Fab")
		)
		(fp_line
			(start 0.67945 -0.305054)
			(end 0.12065 -0.305054)
			(stroke
				(width 0.1)
				(type default)
			)
			(layer "B.Fab")
		)
		(fp_line
			(start 0.12065 0.3048)
			(end 0.67945 0.3048)
			(stroke
				(width 0.1)
				(type default)
			)
			(layer "B.Fab")
		)
		(fp_line
			(start 0.12065 0.2794)
			(end 0.12065 0.3048)
			(stroke
				(width 0.1)
				(type default)
			)
			(layer "B.Fab")
		)
		(fp_line
			(start 0.12065 -0.2794)
			(end -0.12065 -0.2794)
			(stroke
				(width 0.1)
				(type default)
			)
			(layer "B.Fab")
		)
		(fp_line
			(start 0.12065 -0.305054)
			(end 0.12065 -0.2794)
			(stroke
				(width 0.1)
				(type default)
			)
			(layer "B.Fab")
		)
		(fp_line
			(start -0.120396 0.3048)
			(end -0.120396 0.2794)
			(stroke
				(width 0.1)
				(type default)
			)
			(layer "B.Fab")
		)
		(fp_line
			(start -0.120396 0.2794)
			(end 0.12065 0.2794)
			(stroke
				(width 0.1)
				(type default)
			)
			(layer "B.Fab")
		)
		(fp_line
			(start -0.12065 -0.2794)
			(end -0.12065 -0.3048)
			(stroke
				(width 0.1)
				(type default)
			)
			(layer "B.Fab")
		)
		(fp_line
			(start -0.12065 -0.3048)
			(end -0.67945 -0.3048)
			(stroke
				(width 0.1)
				(type default)
			)
			(layer "B.Fab")
		)
		(fp_line
			(start -0.67945 0.3048)
			(end -0.120396 0.3048)
			(stroke
				(width 0.1)
				(type default)
			)
			(layer "B.Fab")
		)
		(fp_line
			(start -0.67945 -0.3048)
			(end -0.67945 0.3048)
			(stroke
				(width 0.1)
				(type default)
			)
			(layer "B.Fab")
		)
		(pad "1" smd circle
			(at 0.40005 0)
			(size 0 0)
			(layers "B.Cu" "B.Mask" "B.Paste")
			(net "P3V3_AUX")
		)
		(pad "2" smd circle
			(at -0.40005 0)
			(size 0 0)
			(layers "B.Cu" "B.Mask" "B.Paste")
			(net "GND")
		)
	)
	(footprint ""
		(layer "B.Cu")
		(at 35.1536 -93.479112)
		(property "Reference" "C2103"
			(at 0 0 0)
			(layer "B.SilkS")
			(hide yes)
			(effects
				(font
					(size 1.27 1.27)
				)
				(justify mirror)
			)
		)
		(property "Value" ""
			(at 0 0 0)
			(layer "B.Fab")
			(effects
				(font
					(size 1.27 1.27)
				)
				(justify mirror)
			)
		)
		(duplicate_pad_numbers_are_jumpers no)
		(fp_line
			(start -2.2098 -0.9398)
			(end -2.2098 0.9398)
			(stroke
				(width 0.1524)
				(type default)
			)
			(layer "B.SilkS")
		)
		(fp_line
			(start -2.2098 0.9398)
			(end 2.2098 0.9398)
			(stroke
				(width 0.1524)
				(type default)
			)
			(layer "B.SilkS")
		)
		(fp_line
			(start 2.2098 -0.9398)
			(end -2.2098 -0.9398)
			(stroke
				(width 0.1524)
				(type default)
			)
			(layer "B.SilkS")
		)
		(fp_line
			(start 2.2098 0.9398)
			(end 2.2098 -0.9398)
			(stroke
				(width 0.1524)
				(type default)
			)
			(layer "B.SilkS")
		)
		(fp_line
			(start -1.700022 -0.899922)
			(end -1.700022 0.899922)
			(stroke
				(width 0.1)
				(type default)
			)
			(layer "B.Fab")
		)
		(fp_line
			(start -1.700022 0.899922)
			(end 1.700022 0.899922)
			(stroke
				(width 0.1)
				(type default)
			)
			(layer "B.Fab")
		)
		(fp_line
			(start 1.700022 -0.899922)
			(end -1.700022 -0.899922)
			(stroke
				(width 0.1)
				(type default)
			)
			(layer "B.Fab")
		)
		(fp_line
			(start 1.700022 0.899922)
			(end 1.700022 -0.899922)
			(stroke
				(width 0.1)
				(type default)
			)
			(layer "B.Fab")
		)
		(pad "1" smd rect
			(at 1.4732 0)
			(size 1.1684 1.5748)
			(layers "B.Cu" "B.Mask" "B.Paste")
			(net "P52V_FAN_2")
		)
		(pad "2" smd rect
			(at -1.4732 0)
			(size 1.1684 1.5748)
			(layers "B.Cu" "B.Mask" "B.Paste")
			(net "GND")
		)
	)
	(footprint ""
		(layer "B.Cu")
		(at 43.0784 -43.085512)
		(property "Reference" "PD10"
			(at 4.826 3.894582 0)
			(unlocked yes)
			(layer "B.SilkS")
			(effects
				(font
					(size 0.7874 0.5842)
					(thickness 0.1524)
				)
				(justify left mirror)
			)
		)
		(property "Value" ""
			(at 0 0 0)
			(layer "B.Fab")
			(effects
				(font
					(size 1.27 1.27)
				)
				(justify mirror)
			)
		)
		(duplicate_pad_numbers_are_jumpers no)
		(fp_line
			(start -5.334 0)
			(end -5.334 -3.109976)
			(stroke
				(width 0.1524)
				(type default)
			)
			(layer "B.SilkS")
		)
		(fp_line
			(start -5.334 3.109976)
			(end -5.334 0)
			(stroke
				(width 0.1524)
				(type default)
			)
			(layer "B.SilkS")
		)
		(fp_line
			(start -5.334 3.109976)
			(end -4.8133 3.109976)
			(stroke
				(width 0.1524)
				(type default)
			)
			(layer "B.SilkS")
		)
		(fp_line
			(start -5.207 3.109976)
			(end -5.207 -3.109976)
			(stroke
				(width 0.1524)
				(type default)
			)
			(layer "B.SilkS")
		)
		(fp_line
			(start -5.1308 3.109976)
			(end -5.1308 -3.109976)
			(stroke
				(width 0.1524)
				(type default)
			)
			(layer "B.SilkS")
		)
		(fp_line
			(start -5.0292 3.109976)
			(end -5.0292 -3.109976)
			(stroke
				(width 0.1524)
				(type default)
			)
			(layer "B.SilkS")
		)
		(fp_line
			(start -4.9276 3.109976)
			(end -4.9276 -3.109976)
			(stroke
				(width 0.1524)
				(type default)
			)
			(layer "B.SilkS")
		)
		(fp_line
			(start -4.826 -3.109976)
			(end -4.826 0)
			(stroke
				(width 0.1524)
				(type default)
			)
			(layer "B.SilkS")
		)
		(fp_line
			(start -4.826 0)
			(end -4.826 3.109976)
			(stroke
				(width 0.1524)
				(type default)
			)
			(layer "B.SilkS")
		)
		(fp_line
			(start -4.826 3.109976)
			(end 4.826 3.109976)
			(stroke
				(width 0.1524)
				(type default)
			)
			(layer "B.SilkS")
		)
		(fp_line
			(start -4.8133 -3.109976)
			(end -5.3467 -3.109976)
			(stroke
				(width 0.1524)
				(type default)
			)
			(layer "B.SilkS")
		)
		(fp_line
			(start -1.143 0)
			(end -1.8034 0)
			(stroke
				(width 0.1524)
				(type default)
			)
			(layer "B.SilkS")
		)
		(fp_line
			(start -1.143 0)
			(end 1.016 -1.016)
			(stroke
				(width 0.1524)
				(type default)
			)
			(layer "B.SilkS")
		)
		(fp_line
			(start -1.143 1.397)
			(end -1.143 -1.397)
			(stroke
				(width 0.1524)
				(type default)
			)
			(layer "B.SilkS")
		)
		(fp_line
			(start 1.016 -1.016)
			(end 1.016 1.016)
			(stroke
				(width 0.1524)
				(type default)
			)
			(layer "B.SilkS")
		)
		(fp_line
			(start 1.016 1.016)
			(end -1.016 0)
			(stroke
				(width 0.1524)
				(type default)
			)
			(layer "B.SilkS")
		)
		(fp_line
			(start 1.0922 0)
			(end 1.7018 0)
			(stroke
				(width 0.1524)
				(type default)
			)
			(layer "B.SilkS")
		)
		(fp_line
			(start 4.826 -3.109976)
			(end -4.826 -3.109976)
			(stroke
				(width 0.1524)
				(type default)
			)
			(layer "B.SilkS")
		)
		(fp_line
			(start 4.826 0)
			(end 4.826 -3.109976)
			(stroke
				(width 0.1524)
				(type default)
			)
			(layer "B.SilkS")
		)
		(fp_line
			(start 4.826 3.109976)
			(end 4.826 0)
			(stroke
				(width 0.1524)
				(type default)
			)
			(layer "B.SilkS")
		)
		(fp_line
			(start -3.554984 -3.109976)
			(end -3.554984 3.109976)
			(stroke
				(width 0.1)
				(type default)
			)
			(layer "B.Fab")
		)
		(fp_line
			(start -3.554984 3.109976)
			(end 3.554984 3.109976)
			(stroke
				(width 0.1)
				(type default)
			)
			(layer "B.Fab")
		)
		(fp_line
			(start -1.143 0)
			(end -1.8034 0)
			(stroke
				(width 0.1)
				(type default)
			)
			(layer "B.Fab")
		)
		(fp_line
			(start -1.143 0)
			(end 1.016 -1.016)
			(stroke
				(width 0.1)
				(type default)
			)
			(layer "B.Fab")
		)
		(fp_line
			(start -1.143 1.397)
			(end -1.143 -1.397)
			(stroke
				(width 0.1)
				(type default)
			)
			(layer "B.Fab")
		)
		(fp_line
			(start 1.016 -1.016)
			(end 1.016 1.016)
			(stroke
				(width 0.1)
				(type default)
			)
			(layer "B.Fab")
		)
		(fp_line
			(start 1.016 1.016)
			(end -1.016 0)
			(stroke
				(width 0.1)
				(type default)
			)
			(layer "B.Fab")
		)
		(fp_line
			(start 1.0922 0)
			(end 1.7018 0)
			(stroke
				(width 0.1)
				(type default)
			)
			(layer "B.Fab")
		)
		(fp_line
			(start 3.554984 -3.109976)
			(end -3.554984 -3.109976)
			(stroke
				(width 0.1)
				(type default)
			)
			(layer "B.Fab")
		)
		(fp_line
			(start 3.554984 3.109976)
			(end 3.554984 -3.109976)
			(stroke
				(width 0.1)
				(type default)
			)
			(layer "B.Fab")
		)
		(fp_text user "-"
			(at -6.6802 0.22225 180)
			(unlocked yes)
			(layer "B.SilkS")
			(effects
				(font
					(size 1.905 1.4224)
					(thickness 0.1524)
				)
				(justify left mirror)
			)
		)
		(fp_text user "+"
			(at 5.5626 0.432562 180)
			(unlocked yes)
			(layer "B.SilkS")
			(effects
				(font
					(size 1.905 1.4224)
					(thickness 0.1524)
				)
				(justify left mirror)
			)
		)
		(fp_text user "-"
			(at -6.6802 0.22225 180)
			(unlocked yes)
			(layer "B.Fab")
			(effects
				(font
					(size 1.905 1.4224)
					(thickness 0.1524)
				)
				(justify left mirror)
			)
		)
		(fp_text user "+"
			(at 4.5466 0.19685 180)
			(unlocked yes)
			(layer "B.Fab")
			(effects
				(font
					(size 1.905 1.4224)
					(thickness 0.1524)
				)
				(justify left mirror)
			)
		)
		(pad "A" smd rect
			(at 3.400044 0)
			(size 2.5146 3.302)
			(layers "B.Cu" "B.Mask" "B.Paste")
			(net "GND")
		)
		(pad "C" smd rect
			(at -3.400044 0)
			(size 2.5146 3.302)
			(layers "B.Cu" "B.Mask" "B.Paste")
			(net "P52V_FAN_3")
		)
	)
	(footprint ""
		(layer "B.Cu")
		(at 40.767 -73.971912 90)
		(property "Reference" "PC31"
			(at 0 0 90)
			(layer "B.SilkS")
			(hide yes)
			(effects
				(font
					(size 1.27 1.27)
				)
				(justify mirror)
			)
		)
		(property "Value" ""
			(at 0 0 90)
			(layer "B.Fab")
			(effects
				(font
					(size 1.27 1.27)
				)
				(justify mirror)
			)
		)
		(duplicate_pad_numbers_are_jumpers no)
		(fp_line
			(start 0.7874 -0.4064)
			(end -0.7874 -0.4064)
			(stroke
				(width 0.1524)
				(type default)
			)
			(layer "B.SilkS")
		)
		(fp_line
			(start -0.7874 -0.4064)
			(end -0.7874 0.4064)
			(stroke
				(width 0.1524)
				(type default)
			)
			(layer "B.SilkS")
		)
		(fp_line
			(start 0.7874 0.4064)
			(end 0.7874 -0.4064)
			(stroke
				(width 0.1524)
				(type default)
			)
			(layer "B.SilkS")
		)
		(fp_line
			(start -0.7874 0.4064)
			(end 0.7874 0.4064)
			(stroke
				(width 0.1524)
				(type default)
			)
			(layer "B.SilkS")
		)
		(fp_line
			(start 0.67945 -0.305054)
			(end 0.12065 -0.305054)
			(stroke
				(width 0.1)
				(type default)
			)
			(layer "B.Fab")
		)
		(fp_line
			(start 0.12065 -0.305054)
			(end 0.12065 -0.2794)
			(stroke
				(width 0.1)
				(type default)
			)
			(layer "B.Fab")
		)
		(fp_line
			(start -0.12065 -0.3048)
			(end -0.67945 -0.3048)
			(stroke
				(width 0.1)
				(type default)
			)
			(layer "B.Fab")
		)
		(fp_line
			(start -0.67945 -0.3048)
			(end -0.67945 0.3048)
			(stroke
				(width 0.1)
				(type default)
			)
			(layer "B.Fab")
		)
		(fp_line
			(start 0.12065 -0.2794)
			(end -0.12065 -0.2794)
			(stroke
				(width 0.1)
				(type default)
			)
			(layer "B.Fab")
		)
		(fp_line
			(start -0.12065 -0.2794)
			(end -0.12065 -0.3048)
			(stroke
				(width 0.1)
				(type default)
			)
			(layer "B.Fab")
		)
		(fp_line
			(start 0.12065 0.2794)
			(end 0.12065 0.3048)
			(stroke
				(width 0.1)
				(type default)
			)
			(layer "B.Fab")
		)
		(fp_line
			(start -0.120396 0.2794)
			(end 0.12065 0.2794)
			(stroke
				(width 0.1)
				(type default)
			)
			(layer "B.Fab")
		)
		(fp_line
			(start 0.67945 0.3048)
			(end 0.67945 -0.305054)
			(stroke
				(width 0.1)
				(type default)
			)
			(layer "B.Fab")
		)
		(fp_line
			(start 0.12065 0.3048)
			(end 0.67945 0.3048)
			(stroke
				(width 0.1)
				(type default)
			)
			(layer "B.Fab")
		)
		(fp_line
			(start -0.120396 0.3048)
			(end -0.120396 0.2794)
			(stroke
				(width 0.1)
				(type default)
			)
			(layer "B.Fab")
		)
		(fp_line
			(start -0.67945 0.3048)
			(end -0.120396 0.3048)
			(stroke
				(width 0.1)
				(type default)
			)
			(layer "B.Fab")
		)
		(pad "1" smd circle
			(at 0.40005 0 270)
			(size 0 0)
			(layers "B.Cu" "B.Mask" "B.Paste")
			(net "FAN_2_P3V_R")
		)
		(pad "2" smd circle
			(at -0.40005 0 270)
			(size 0 0)
			(layers "B.Cu" "B.Mask" "B.Paste")
			(net "GND")
		)
	)
	(footprint ""
		(layer "B.Cu")
		(at 39.365428 -252.894846 180)
		(property "Reference" "U379"
			(at -3.432302 -0.037846 270)
			(unlocked yes)
			(layer "B.SilkS")
			(effects
				(font
					(size 0.7874 0.5842)
					(thickness 0.1524)
				)
				(justify mirror)
			)
		)
		(property "Value" ""
			(at 0 0 0)
			(layer "B.Fab")
			(effects
				(font
					(size 1.27 1.27)
				)
				(justify mirror)
			)
		)
		(duplicate_pad_numbers_are_jumpers no)
		(fp_line
			(start 1.7018 1.1176)
			(end 1.7018 -1.1176)
			(stroke
				(width 0.1524)
				(type default)
			)
			(layer "B.SilkS")
		)
		(fp_line
			(start 0.254 -1.1176)
			(end 1.7018 -1.1176)
			(stroke
				(width 0.1524)
				(type default)
			)
			(layer "B.SilkS")
		)
		(fp_line
			(start 0 -0.7112)
			(end 0.254 -1.1176)
			(stroke
				(width 0.1524)
				(type default)
			)
			(layer "B.SilkS")
		)
		(fp_line
			(start -0.254 -1.1176)
			(end 0 -0.7112)
			(stroke
				(width 0.1524)
				(type default)
			)
			(layer "B.SilkS")
		)
		(fp_line
			(start -1.7018 1.1176)
			(end 1.7018 1.1176)
			(stroke
				(width 0.1524)
				(type default)
			)
			(layer "B.SilkS")
		)
		(fp_line
			(start -1.7018 -1.1176)
			(end -0.254 -1.1176)
			(stroke
				(width 0.1524)
				(type default)
			)
			(layer "B.SilkS")
		)
		(fp_line
			(start -1.7018 -1.1176)
			(end -1.7018 1.1176)
			(stroke
				(width 0.1524)
				(type default)
			)
			(layer "B.SilkS")
		)
		(fp_poly
			(pts
				(xy 1.8161 -0.675386) (xy 2.4003 -0.446786) (xy 2.4003 -0.878586)
			)
			(stroke
				(width 0)
				(type default)
			)
			(fill yes)
			(layer "B.SilkS")
		)
		(fp_line
			(start 1.5494 1.1176)
			(end 1.5494 -1.1176)
			(stroke
				(width 0.1)
				(type default)
			)
			(layer "B.Fab")
		)
		(fp_line
			(start 0.254 -1.1176)
			(end 1.5494 -1.1176)
			(stroke
				(width 0.1)
				(type default)
			)
			(layer "B.Fab")
		)
		(fp_line
			(start -0.254 -1.1176)
			(end 0.254 -1.1176)
			(stroke
				(width 0.1)
				(type default)
			)
			(layer "B.Fab")
		)
		(fp_line
			(start -1.5494 1.1176)
			(end 1.5494 1.1176)
			(stroke
				(width 0.1)
				(type default)
			)
			(layer "B.Fab")
		)
		(fp_line
			(start -1.5494 -1.1176)
			(end -0.254 -1.1176)
			(stroke
				(width 0.1)
				(type default)
			)
			(layer "B.Fab")
		)
		(fp_line
			(start -1.5494 -1.1176)
			(end -1.5494 1.1176)
			(stroke
				(width 0.1)
				(type default)
			)
			(layer "B.Fab")
		)
		(fp_poly
			(pts
				(xy 1.8161 -0.675386) (xy 2.4003 -0.446786) (xy 2.4003 -0.878586)
			)
			(stroke
				(width 0)
				(type default)
			)
			(fill yes)
			(layer "B.Fab")
		)
		(pad "1" smd rect
			(at 0.962406 -0.649986 90)
			(size 0.3302 1.1684)
			(layers "B.Cu" "B.Mask" "B.Paste")
			(net "FAN_1_PRESENT_R")
		)
		(pad "2" smd rect
			(at 0.962406 0 90)
			(size 0.3302 1.1684)
			(layers "B.Cu" "B.Mask" "B.Paste")
			(net "P52V_FAN_1_BUFF_EN_R")
		)
		(pad "3" smd rect
			(at 0.962406 0.649986 90)
			(size 0.3302 1.1684)
			(layers "B.Cu" "B.Mask" "B.Paste")
			(net "GND")
		)
		(pad "4" smd rect
			(at -0.962406 0.649986 90)
			(size 0.3302 1.1684)
			(layers "B.Cu" "B.Mask" "B.Paste")
			(net "P52V_FAN_1_EN")
		)
		(pad "5" smd rect
			(at -0.962406 -0.649986 90)
			(size 0.3302 1.1684)
			(layers "B.Cu" "B.Mask" "B.Paste")
			(net "P3V3_AUX")
		)
	)
)
